(kicad_pcb
	(version 20260206)
	(generator "pcbnew")
	(generator_version "10.0")
	(general
		(thickness 1.6)
		(legacy_teardrops no)
	)
	(paper "A4")
	(title_block
		(title "01162023_DA0F0TEBIF0_F0T_Expander_BD_F_brd_V02_OCP.brd")
		(comment 1 "Grand Teton / footprints 1756-1761 of 9728")
	)
	(layers
		(0 "F.Cu" signal "TOP")
		(4 "In1.Cu" signal "GND")
		(6 "In2.Cu" signal "VCC")
		(8 "In3.Cu" signal "VCC1")
		(10 "In4.Cu" signal "GND1")
		(12 "In5.Cu" signal "IN1")
		(14 "In6.Cu" signal "GND2")
		(16 "In7.Cu" signal "IN2")
		(18 "In8.Cu" signal "GND3")
		(20 "In9.Cu" signal "IN3")
		(22 "In10.Cu" signal "GND4")
		(24 "In11.Cu" signal "IN4")
		(26 "In12.Cu" signal "GND5")
		(28 "In13.Cu" signal "IN5")
		(30 "In14.Cu" signal "GND6")
		(32 "In15.Cu" signal "IN6")
		(34 "In16.Cu" signal "GND7")
		(2 "B.Cu" signal "BOTTOM")
		(9 "F.Adhes" user "F.Adhesive")
		(11 "B.Adhes" user "B.Adhesive")
		(13 "F.Paste" user "Package Geometry/Pastemask Top")
		(15 "B.Paste" user "Package Geometry/Pastemask Bottom")
		(5 "F.SilkS" user "Ref Des/Silkscreen Top")
		(7 "B.SilkS" user "Ref Des/Silkscreen Bottom")
		(1 "F.Mask" user "Board Geometry/Soldermask Top")
		(3 "B.Mask" user "Board Geometry/Soldermask Bottom")
		(17 "Dwgs.User" user "User.Drawings")
		(19 "Cmts.User" user "User.Comments")
		(21 "Eco1.User" user "User.Eco1")
		(23 "Eco2.User" user "User.Eco2")
		(25 "Edge.Cuts" user "Board Geometry/Outline")
		(27 "Margin" user)
		(31 "F.CrtYd" user "Package Geometry/Place Bound Top")
		(29 "B.CrtYd" user "Package Geometry/Place Bound Bottom")
		(35 "F.Fab" user "Ref Des/Assembly Top")
		(33 "B.Fab" user "Ref Des/Assembly Bottom")
	)
	(footprint ""
		(layer "F.Cu")
		(at 377.3805 -356.244906 90)
		(property "Reference" "C768"
			(at 0 0 90)
			(layer "F.SilkS")
			(hide yes)
			(effects
				(font
					(size 1.27 1.27)
				)
			)
		)
		(property "Value" ""
			(at 0 0 90)
			(layer "F.Fab")
			(effects
				(font
					(size 1.27 1.27)
				)
			)
		)
		(duplicate_pad_numbers_are_jumpers no)
		(fp_line
			(start 0.299974 -0.150114)
			(end 0.299974 0.150114)
			(stroke
				(width 0.1)
				(type default)
			)
			(layer "F.Fab")
		)
		(fp_line
			(start -0.299974 -0.150114)
			(end 0.299974 -0.150114)
			(stroke
				(width 0.1)
				(type default)
			)
			(layer "F.Fab")
		)
		(fp_line
			(start 0.299974 0.150114)
			(end -0.299974 0.150114)
			(stroke
				(width 0.1)
				(type default)
			)
			(layer "F.Fab")
		)
		(fp_line
			(start -0.299974 0.150114)
			(end -0.299974 -0.150114)
			(stroke
				(width 0.1)
				(type default)
			)
			(layer "F.Fab")
		)
		(pad "1" smd rect
			(at -0.2667 0 90)
			(size 0.3048 0.381)
			(layers "F.Cu" "F.Mask" "F.Paste")
			(net "P5E_PEX3_STN6_TX_DP<108>")
		)
		(pad "2" smd rect
			(at 0.2667 0 90)
			(size 0.3048 0.381)
			(layers "F.Cu" "F.Mask" "F.Paste")
			(net "P5E_PEX3_STN6_TX_C_DP<108>")
		)
	)
	(footprint ""
		(layer "F.Cu")
		(at 111.291878 -128.170686 90)
		(property "Reference" "PC300"
			(at 0 0 90)
			(layer "F.SilkS")
			(hide yes)
			(effects
				(font
					(size 1.27 1.27)
				)
			)
		)
		(property "Value" ""
			(at 0 0 90)
			(layer "F.Fab")
			(effects
				(font
					(size 1.27 1.27)
				)
			)
		)
		(duplicate_pad_numbers_are_jumpers no)
		(fp_line
			(start 0.7874 -0.4064)
			(end 0.7874 0.4064)
			(stroke
				(width 0.1524)
				(type default)
			)
			(layer "F.SilkS")
		)
		(fp_line
			(start -0.7874 -0.4064)
			(end 0.7874 -0.4064)
			(stroke
				(width 0.1524)
				(type default)
			)
			(layer "F.SilkS")
		)
		(fp_line
			(start 0.7874 0.4064)
			(end -0.7874 0.4064)
			(stroke
				(width 0.1524)
				(type default)
			)
			(layer "F.SilkS")
		)
		(fp_line
			(start -0.7874 0.4064)
			(end -0.7874 -0.4064)
			(stroke
				(width 0.1524)
				(type default)
			)
			(layer "F.SilkS")
		)
		(fp_line
			(start -0.12065 -0.305054)
			(end -0.12065 -0.2794)
			(stroke
				(width 0.1)
				(type default)
			)
			(layer "F.Fab")
		)
		(fp_line
			(start -0.67945 -0.305054)
			(end -0.12065 -0.305054)
			(stroke
				(width 0.1)
				(type default)
			)
			(layer "F.Fab")
		)
		(fp_line
			(start 0.67945 -0.3048)
			(end 0.67945 0.3048)
			(stroke
				(width 0.1)
				(type default)
			)
			(layer "F.Fab")
		)
		(fp_line
			(start 0.12065 -0.3048)
			(end 0.67945 -0.3048)
			(stroke
				(width 0.1)
				(type default)
			)
			(layer "F.Fab")
		)
		(fp_line
			(start 0.12065 -0.2794)
			(end 0.12065 -0.3048)
			(stroke
				(width 0.1)
				(type default)
			)
			(layer "F.Fab")
		)
		(fp_line
			(start -0.12065 -0.2794)
			(end 0.12065 -0.2794)
			(stroke
				(width 0.1)
				(type default)
			)
			(layer "F.Fab")
		)
		(fp_line
			(start 0.120396 0.2794)
			(end -0.12065 0.2794)
			(stroke
				(width 0.1)
				(type default)
			)
			(layer "F.Fab")
		)
		(fp_line
			(start -0.12065 0.2794)
			(end -0.12065 0.3048)
			(stroke
				(width 0.1)
				(type default)
			)
			(layer "F.Fab")
		)
		(fp_line
			(start 0.67945 0.3048)
			(end 0.120396 0.3048)
			(stroke
				(width 0.1)
				(type default)
			)
			(layer "F.Fab")
		)
		(fp_line
			(start 0.120396 0.3048)
			(end 0.120396 0.2794)
			(stroke
				(width 0.1)
				(type default)
			)
			(layer "F.Fab")
		)
		(fp_line
			(start -0.12065 0.3048)
			(end -0.67945 0.3048)
			(stroke
				(width 0.1)
				(type default)
			)
			(layer "F.Fab")
		)
		(fp_line
			(start -0.67945 0.3048)
			(end -0.67945 -0.305054)
			(stroke
				(width 0.1)
				(type default)
			)
			(layer "F.Fab")
		)
		(pad "1" smd circle
			(at -0.40005 0 90)
			(size 0 0)
			(layers "F.Cu" "F.Mask" "F.Paste")
			(net "P3V3")
		)
		(pad "2" smd circle
			(at 0.40005 0 90)
			(size 0 0)
			(layers "F.Cu" "F.Mask" "F.Paste")
			(net "GND")
		)
	)
	(footprint ""
		(layer "F.Cu")
		(at 209.103976 -291.722048 90)
		(property "Reference" "C2756"
			(at 0 0 90)
			(layer "F.SilkS")
			(hide yes)
			(effects
				(font
					(size 1.27 1.27)
				)
			)
		)
		(property "Value" ""
			(at 0 0 90)
			(layer "F.Fab")
			(effects
				(font
					(size 1.27 1.27)
				)
			)
		)
		(duplicate_pad_numbers_are_jumpers no)
		(fp_line
			(start 0.7874 -0.4064)
			(end 0.7874 0.4064)
			(stroke
				(width 0.1524)
				(type default)
			)
			(layer "F.SilkS")
		)
		(fp_line
			(start -0.7874 -0.4064)
			(end 0.7874 -0.4064)
			(stroke
				(width 0.1524)
				(type default)
			)
			(layer "F.SilkS")
		)
		(fp_line
			(start 0.7874 0.4064)
			(end -0.7874 0.4064)
			(stroke
				(width 0.1524)
				(type default)
			)
			(layer "F.SilkS")
		)
		(fp_line
			(start -0.7874 0.4064)
			(end -0.7874 -0.4064)
			(stroke
				(width 0.1524)
				(type default)
			)
			(layer "F.SilkS")
		)
		(fp_line
			(start -0.12065 -0.305054)
			(end -0.12065 -0.2794)
			(stroke
				(width 0.1)
				(type default)
			)
			(layer "F.Fab")
		)
		(fp_line
			(start -0.67945 -0.305054)
			(end -0.12065 -0.305054)
			(stroke
				(width 0.1)
				(type default)
			)
			(layer "F.Fab")
		)
		(fp_line
			(start 0.67945 -0.3048)
			(end 0.67945 0.3048)
			(stroke
				(width 0.1)
				(type default)
			)
			(layer "F.Fab")
		)
		(fp_line
			(start 0.12065 -0.3048)
			(end 0.67945 -0.3048)
			(stroke
				(width 0.1)
				(type default)
			)
			(layer "F.Fab")
		)
		(fp_line
			(start 0.12065 -0.2794)
			(end 0.12065 -0.3048)
			(stroke
				(width 0.1)
				(type default)
			)
			(layer "F.Fab")
		)
		(fp_line
			(start -0.12065 -0.2794)
			(end 0.12065 -0.2794)
			(stroke
				(width 0.1)
				(type default)
			)
			(layer "F.Fab")
		)
		(fp_line
			(start 0.120396 0.2794)
			(end -0.12065 0.2794)
			(stroke
				(width 0.1)
				(type default)
			)
			(layer "F.Fab")
		)
		(fp_line
			(start -0.12065 0.2794)
			(end -0.12065 0.3048)
			(stroke
				(width 0.1)
				(type default)
			)
			(layer "F.Fab")
		)
		(fp_line
			(start 0.67945 0.3048)
			(end 0.120396 0.3048)
			(stroke
				(width 0.1)
				(type default)
			)
			(layer "F.Fab")
		)
		(fp_line
			(start 0.120396 0.3048)
			(end 0.120396 0.2794)
			(stroke
				(width 0.1)
				(type default)
			)
			(layer "F.Fab")
		)
		(fp_line
			(start -0.12065 0.3048)
			(end -0.67945 0.3048)
			(stroke
				(width 0.1)
				(type default)
			)
			(layer "F.Fab")
		)
		(fp_line
			(start -0.67945 0.3048)
			(end -0.67945 -0.305054)
			(stroke
				(width 0.1)
				(type default)
			)
			(layer "F.Fab")
		)
		(pad "1" smd circle
			(at -0.40005 0 90)
			(size 0 0)
			(layers "F.Cu" "F.Mask" "F.Paste")
			(net "GND")
		)
		(pad "2" smd circle
			(at 0.40005 0 90)
			(size 0 0)
			(layers "F.Cu" "F.Mask" "F.Paste")
			(net "P3V3_AUX")
		)
	)
	(footprint ""
		(layer "F.Cu")
		(at 381.43561 -308.13375 -135)
		(property "Reference" "R1401"
			(at 0 0 225)
			(layer "F.SilkS")
			(hide yes)
			(effects
				(font
					(size 1.27 1.27)
				)
			)
		)
		(property "Value" ""
			(at 0 0 225)
			(layer "F.Fab")
			(effects
				(font
					(size 1.27 1.27)
				)
			)
		)
		(duplicate_pad_numbers_are_jumpers no)
		(fp_line
			(start 0.787389 0.406267)
			(end -0.787389 0.406267)
			(stroke
				(width 0.1524)
				(type default)
			)
			(layer "F.SilkS")
		)
		(fp_line
			(start 0.787389 -0.406267)
			(end 0.787389 0.406267)
			(stroke
				(width 0.1524)
				(type default)
			)
			(layer "F.SilkS")
		)
		(fp_line
			(start -0.787389 0.406267)
			(end -0.787389 -0.406267)
			(stroke
				(width 0.1524)
				(type default)
			)
			(layer "F.SilkS")
		)
		(fp_line
			(start -0.787389 -0.406267)
			(end 0.787389 -0.406267)
			(stroke
				(width 0.1524)
				(type default)
			)
			(layer "F.SilkS")
		)
		(fp_line
			(start 0.679446 0.30479)
			(end 0.120515 0.30479)
			(stroke
				(width 0.1)
				(type default)
			)
			(layer "F.Fab")
		)
		(fp_line
			(start 0.120515 0.30479)
			(end 0.120335 0.279466)
			(stroke
				(width 0.1)
				(type default)
			)
			(layer "F.Fab")
		)
		(fp_line
			(start 0.120335 0.279466)
			(end -0.120695 0.279466)
			(stroke
				(width 0.1)
				(type default)
			)
			(layer "F.Fab")
		)
		(fp_line
			(start 0.679446 -0.30479)
			(end 0.679446 0.30479)
			(stroke
				(width 0.1)
				(type default)
			)
			(layer "F.Fab")
		)
		(fp_line
			(start -0.120515 0.30479)
			(end -0.679446 0.30479)
			(stroke
				(width 0.1)
				(type default)
			)
			(layer "F.Fab")
		)
		(fp_line
			(start -0.120695 0.279466)
			(end -0.120515 0.30479)
			(stroke
				(width 0.1)
				(type default)
			)
			(layer "F.Fab")
		)
		(fp_line
			(start 0.120695 -0.279466)
			(end 0.120515 -0.30479)
			(stroke
				(width 0.1)
				(type default)
			)
			(layer "F.Fab")
		)
		(fp_line
			(start 0.120515 -0.30479)
			(end 0.679446 -0.30479)
			(stroke
				(width 0.1)
				(type default)
			)
			(layer "F.Fab")
		)
		(fp_line
			(start -0.679446 0.30479)
			(end -0.679446 -0.305149)
			(stroke
				(width 0.1)
				(type default)
			)
			(layer "F.Fab")
		)
		(fp_line
			(start -0.120695 -0.279466)
			(end 0.120695 -0.279466)
			(stroke
				(width 0.1)
				(type default)
			)
			(layer "F.Fab")
		)
		(fp_line
			(start -0.120695 -0.304969)
			(end -0.120695 -0.279466)
			(stroke
				(width 0.1)
				(type default)
			)
			(layer "F.Fab")
		)
		(fp_line
			(start -0.679446 -0.305149)
			(end -0.120695 -0.304969)
			(stroke
				(width 0.1)
				(type default)
			)
			(layer "F.Fab")
		)
		(pad "1" smd circle
			(at -0.40005 0 225)
			(size 0 0)
			(layers "F.Cu" "F.Mask" "F.Paste")
			(net "PEX3_DBG_MODE1")
		)
		(pad "2" smd circle
			(at 0.40005 0 225)
			(size 0 0)
			(layers "F.Cu" "F.Mask" "F.Paste")
			(net "P1V8_PEX")
		)
	)
	(footprint ""
		(layer "F.Cu")
		(at 338.291424 -268.278102 -90)
		(property "Reference" "PC984"
			(at 0 0 270)
			(layer "F.SilkS")
			(hide yes)
			(effects
				(font
					(size 1.27 1.27)
				)
			)
		)
		(property "Value" ""
			(at 0 0 270)
			(layer "F.Fab")
			(effects
				(font
					(size 1.27 1.27)
				)
			)
		)
		(duplicate_pad_numbers_are_jumpers no)
		(fp_line
			(start -0.7874 0.4064)
			(end -0.7874 -0.4064)
			(stroke
				(width 0.1524)
				(type default)
			)
			(layer "F.SilkS")
		)
		(fp_line
			(start 0.7874 0.4064)
			(end -0.7874 0.4064)
			(stroke
				(width 0.1524)
				(type default)
			)
			(layer "F.SilkS")
		)
		(fp_line
			(start -0.7874 -0.4064)
			(end 0.7874 -0.4064)
			(stroke
				(width 0.1524)
				(type default)
			)
			(layer "F.SilkS")
		)
		(fp_line
			(start 0.7874 -0.4064)
			(end 0.7874 0.4064)
			(stroke
				(width 0.1524)
				(type default)
			)
			(layer "F.SilkS")
		)
		(fp_line
			(start -0.67945 0.3048)
			(end -0.67945 -0.305054)
			(stroke
				(width 0.1)
				(type default)
			)
			(layer "F.Fab")
		)
		(fp_line
			(start -0.12065 0.3048)
			(end -0.67945 0.3048)
			(stroke
				(width 0.1)
				(type default)
			)
			(layer "F.Fab")
		)
		(fp_line
			(start 0.120396 0.3048)
			(end 0.120396 0.2794)
			(stroke
				(width 0.1)
				(type default)
			)
			(layer "F.Fab")
		)
		(fp_line
			(start 0.67945 0.3048)
			(end 0.120396 0.3048)
			(stroke
				(width 0.1)
				(type default)
			)
			(layer "F.Fab")
		)
		(fp_line
			(start -0.12065 0.2794)
			(end -0.12065 0.3048)
			(stroke
				(width 0.1)
				(type default)
			)
			(layer "F.Fab")
		)
		(fp_line
			(start 0.120396 0.2794)
			(end -0.12065 0.2794)
			(stroke
				(width 0.1)
				(type default)
			)
			(layer "F.Fab")
		)
		(fp_line
			(start -0.12065 -0.2794)
			(end 0.12065 -0.2794)
			(stroke
				(width 0.1)
				(type default)
			)
			(layer "F.Fab")
		)
		(fp_line
			(start 0.12065 -0.2794)
			(end 0.12065 -0.3048)
			(stroke
				(width 0.1)
				(type default)
			)
			(layer "F.Fab")
		)
		(fp_line
			(start 0.12065 -0.3048)
			(end 0.67945 -0.3048)
			(stroke
				(width 0.1)
				(type default)
			)
			(layer "F.Fab")
		)
		(fp_line
			(start 0.67945 -0.3048)
			(end 0.67945 0.3048)
			(stroke
				(width 0.1)
				(type default)
			)
			(layer "F.Fab")
		)
		(fp_line
			(start -0.67945 -0.305054)
			(end -0.12065 -0.305054)
			(stroke
				(width 0.1)
				(type default)
			)
			(layer "F.Fab")
		)
		(fp_line
			(start -0.12065 -0.305054)
			(end -0.12065 -0.2794)
			(stroke
				(width 0.1)
				(type default)
			)
			(layer "F.Fab")
		)
		(pad "1" smd circle
			(at -0.40005 0 270)
			(size 0 0)
			(layers "F.Cu" "F.Mask" "F.Paste")
			(net "P12V_AUX")
		)
		(pad "2" smd circle
			(at 0.40005 0 270)
			(size 0 0)
			(layers "F.Cu" "F.Mask" "F.Paste")
			(net "GND")
		)
	)
	(footprint ""
		(layer "F.Cu")
		(at 434.29428 -304.31486 90)
		(property "Reference" "R3994"
			(at 0 0 90)
			(layer "F.SilkS")
			(hide yes)
			(effects
				(font
					(size 1.27 1.27)
				)
			)
		)
		(property "Value" ""
			(at 0 0 90)
			(layer "F.Fab")
			(effects
				(font
					(size 1.27 1.27)
				)
			)
		)
		(duplicate_pad_numbers_are_jumpers no)
		(fp_line
			(start 0.7874 -0.4064)
			(end 0.7874 0.4064)
			(stroke
				(width 0.1524)
				(type default)
			)
			(layer "F.SilkS")
		)
		(fp_line
			(start -0.7874 -0.4064)
			(end 0.7874 -0.4064)
			(stroke
				(width 0.1524)
				(type default)
			)
			(layer "F.SilkS")
		)
		(fp_line
			(start 0.7874 0.4064)
			(end -0.7874 0.4064)
			(stroke
				(width 0.1524)
				(type default)
			)
			(layer "F.SilkS")
		)
		(fp_line
			(start -0.7874 0.4064)
			(end -0.7874 -0.4064)
			(stroke
				(width 0.1524)
				(type default)
			)
			(layer "F.SilkS")
		)
		(fp_line
			(start -0.12065 -0.305054)
			(end -0.12065 -0.2794)
			(stroke
				(width 0.1)
				(type default)
			)
			(layer "F.Fab")
		)
		(fp_line
			(start -0.67945 -0.305054)
			(end -0.12065 -0.305054)
			(stroke
				(width 0.1)
				(type default)
			)
			(layer "F.Fab")
		)
		(fp_line
			(start 0.67945 -0.3048)
			(end 0.67945 0.3048)
			(stroke
				(width 0.1)
				(type default)
			)
			(layer "F.Fab")
		)
		(fp_line
			(start 0.12065 -0.3048)
			(end 0.67945 -0.3048)
			(stroke
				(width 0.1)
				(type default)
			)
			(layer "F.Fab")
		)
		(fp_line
			(start 0.12065 -0.2794)
			(end 0.12065 -0.3048)
			(stroke
				(width 0.1)
				(type default)
			)
			(layer "F.Fab")
		)
		(fp_line
			(start -0.12065 -0.2794)
			(end 0.12065 -0.2794)
			(stroke
				(width 0.1)
				(type default)
			)
			(layer "F.Fab")
		)
		(fp_line
			(start 0.120396 0.2794)
			(end -0.12065 0.2794)
			(stroke
				(width 0.1)
				(type default)
			)
			(layer "F.Fab")
		)
		(fp_line
			(start -0.12065 0.2794)
			(end -0.12065 0.3048)
			(stroke
				(width 0.1)
				(type default)
			)
			(layer "F.Fab")
		)
		(fp_line
			(start 0.67945 0.3048)
			(end 0.120396 0.3048)
			(stroke
				(width 0.1)
				(type default)
			)
			(layer "F.Fab")
		)
		(fp_line
			(start 0.120396 0.3048)
			(end 0.120396 0.2794)
			(stroke
				(width 0.1)
				(type default)
			)
			(layer "F.Fab")
		)
		(fp_line
			(start -0.12065 0.3048)
			(end -0.67945 0.3048)
			(stroke
				(width 0.1)
				(type default)
			)
			(layer "F.Fab")
		)
		(fp_line
			(start -0.67945 0.3048)
			(end -0.67945 -0.305054)
			(stroke
				(width 0.1)
				(type default)
			)
			(layer "F.Fab")
		)
		(pad "1" smd circle
			(at -0.40005 0 90)
			(size 0 0)
			(layers "F.Cu" "F.Mask" "F.Paste")
			(net "SMB_PEX3_SLAVE_SCL")
		)
		(pad "2" smd circle
			(at 0.40005 0 90)
			(size 0 0)
			(layers "F.Cu" "F.Mask" "F.Paste")
			(net "SMB_PEX3_R_SCL")
		)
	)
)
